(kicad_pcb
	(version 20260206)
	(generator "pcbnew")
	(generator_version "10.0")
	(general
		(thickness 1.6)
		(legacy_teardrops no)
	)
	(paper "A4")
	(title_block
		(title "v1-tray-backplane — T6M_tray_BP_c_1023_1120.brd")
		(comment 1 "Open CloudServer (Microsoft) / footprint 75 of 170 (J3), pads 1-25 of 25")
	)
	(layers
		(0 "F.Cu" signal "TOP")
		(4 "In1.Cu" signal "GND")
		(6 "In2.Cu" signal "IN1")
		(8 "In3.Cu" signal "VCC")
		(10 "In4.Cu" signal "VCC1")
		(12 "In5.Cu" signal "IN2")
		(14 "In6.Cu" signal "GND1")
		(2 "B.Cu" signal "BOTTOM")
		(9 "F.Adhes" user "F.Adhesive")
		(11 "B.Adhes" user "B.Adhesive")
		(13 "F.Paste" user "Package Geometry/Pastemask Top")
		(15 "B.Paste" user "Package Geometry/Pastemask Bottom")
		(5 "F.SilkS" user "Ref Des/Silkscreen Top")
		(7 "B.SilkS" user "Ref Des/Silkscreen Bottom")
		(1 "F.Mask" user "Board Geometry/Soldermask Top")
		(3 "B.Mask" user "Board Geometry/Soldermask Bottom")
		(17 "Dwgs.User" user "User.Drawings")
		(19 "Cmts.User" user "User.Comments")
		(21 "Eco1.User" user "User.Eco1")
		(23 "Eco2.User" user "User.Eco2")
		(25 "Edge.Cuts" user "Board Geometry/Outline")
		(27 "Margin" user)
		(31 "F.CrtYd" user "Package Geometry/Place Bound Top")
		(29 "B.CrtYd" user "Package Geometry/Place Bound Bottom")
		(35 "F.Fab" user "Ref Des/Assembly Top")
		(33 "B.Fab" user "Ref Des/Assembly Bottom")
	)
	(footprint ""
		(layer "F.Cu")
		(at 85.320124 -14.999716)
		(property "Reference" "J3"
			(at -4.966208 -7.545832 0)
			(unlocked yes)
			(layer "F.SilkS")
			(effects
				(font
					(size 0.7874 0.5842)
					(thickness 0.1524)
				)
				(justify left)
			)
		)
		(property "Value" ""
			(at 0 0 0)
			(layer "F.Fab")
			(effects
				(font
					(size 1.27 1.27)
				)
			)
		)
		(duplicate_pad_numbers_are_jumpers no)
		(pad "" np_thru_hole circle
			(at 3.999992 5.500116)
			(size 2.159 2.159)
			(drill 2.159)
			(layers "*.Cu" "*.Mask")
			(clearance 0.381)
			(thermal_gap 0.381)
		)
		(pad "A1" thru_hole rect
			(at 0 0)
			(size 1.1684 1.1684)
			(drill 0.762)
			(layers "*.Cu" "*.Mask")
			(remove_unused_layers no)
			(net "GND")
			(clearance 0.0508)
			(thermal_gap 0.0508)
			(padstack
				(mode front_inner_back)
				(layer "Inner"
					(shape circle)
					(size 1.1684 1.1684)
					(clearance 0.0508)
				)
				(layer "B.Cu"
					(shape rect)
					(size 1.1684 1.1684)
					(clearance 0.0508)
				)
			)
		)
		(pad "A2" thru_hole circle
			(at 0 1.999996)
			(size 1.1684 1.1684)
			(drill 0.762)
			(layers "*.Cu" "*.Mask")
			(remove_unused_layers no)
			(net "GND")
			(clearance 0.0508)
			(thermal_gap 0.0508)
		)
		(pad "A3" thru_hole circle
			(at 0 3.999992)
			(size 1.1684 1.1684)
			(drill 0.762)
			(layers "*.Cu" "*.Mask")
			(remove_unused_layers no)
			(net "GND")
			(clearance 0.0508)
			(thermal_gap 0.0508)
		)
		(pad "A4" thru_hole circle
			(at 1.999996 0)
			(size 1.1684 1.1684)
			(drill 0.762)
			(layers "*.Cu" "*.Mask")
			(remove_unused_layers no)
			(net "GND")
			(clearance 0.0508)
			(thermal_gap 0.0508)
		)
		(pad "A5" thru_hole circle
			(at 1.999996 1.999996)
			(size 1.1684 1.1684)
			(drill 0.762)
			(layers "*.Cu" "*.Mask")
			(remove_unused_layers no)
			(net "GND")
			(clearance 0.0508)
			(thermal_gap 0.0508)
		)
		(pad "A6" thru_hole circle
			(at 1.999996 3.999992)
			(size 1.1684 1.1684)
			(drill 0.762)
			(layers "*.Cu" "*.Mask")
			(remove_unused_layers no)
			(net "GND")
			(clearance 0.0508)
			(thermal_gap 0.0508)
		)
		(pad "B1" thru_hole circle
			(at 7.999984 0)
			(size 1.1684 1.1684)
			(drill 0.762)
			(layers "*.Cu" "*.Mask")
			(remove_unused_layers no)
			(net "P12V")
			(clearance 0.0508)
			(thermal_gap 0.0508)
		)
		(pad "B2" thru_hole circle
			(at 7.999984 1.999996)
			(size 1.1684 1.1684)
			(drill 0.762)
			(layers "*.Cu" "*.Mask")
			(remove_unused_layers no)
			(net "P12V")
			(clearance 0.0508)
			(thermal_gap 0.0508)
		)
		(pad "B3" thru_hole circle
			(at 7.999984 3.999992)
			(size 1.1684 1.1684)
			(drill 0.762)
			(layers "*.Cu" "*.Mask")
			(remove_unused_layers no)
			(net "P12V")
			(clearance 0.0508)
			(thermal_gap 0.0508)
		)
		(pad "B4" thru_hole circle
			(at 5.999988 0)
			(size 1.1684 1.1684)
			(drill 0.762)
			(layers "*.Cu" "*.Mask")
			(remove_unused_layers no)
			(net "P12V")
			(clearance 0.0508)
			(thermal_gap 0.0508)
		)
		(pad "B5" thru_hole circle
			(at 5.999988 1.999996)
			(size 1.1684 1.1684)
			(drill 0.762)
			(layers "*.Cu" "*.Mask")
			(remove_unused_layers no)
			(net "P12V")
			(clearance 0.0508)
			(thermal_gap 0.0508)
		)
		(pad "B6" thru_hole circle
			(at 5.999988 3.999992)
			(size 1.1684 1.1684)
			(drill 0.762)
			(layers "*.Cu" "*.Mask")
			(remove_unused_layers no)
			(net "P12V")
			(clearance 0.0508)
			(thermal_gap 0.0508)
		)
		(pad "C1" thru_hole circle
			(at 7.999984 7.999984)
			(size 1.1684 1.1684)
			(drill 0.762)
			(layers "*.Cu" "*.Mask")
			(remove_unused_layers no)
			(net "P12V")
			(clearance 0.0508)
			(thermal_gap 0.0508)
		)
		(pad "C2" thru_hole circle
			(at 7.999984 9.99998)
			(size 1.1684 1.1684)
			(drill 0.762)
			(layers "*.Cu" "*.Mask")
			(remove_unused_layers no)
			(net "P12V")
			(clearance 0.0508)
			(thermal_gap 0.0508)
		)
		(pad "C3" thru_hole circle
			(at 7.999984 11.999976)
			(size 1.1684 1.1684)
			(drill 0.762)
			(layers "*.Cu" "*.Mask")
			(remove_unused_layers no)
			(net "P12V")
			(clearance 0.0508)
			(thermal_gap 0.0508)
		)
		(pad "C4" thru_hole circle
			(at 5.999988 7.999984)
			(size 1.1684 1.1684)
			(drill 0.762)
			(layers "*.Cu" "*.Mask")
			(remove_unused_layers no)
			(net "P12V")
			(clearance 0.0508)
			(thermal_gap 0.0508)
		)
		(pad "C5" thru_hole circle
			(at 5.999988 9.99998)
			(size 1.1684 1.1684)
			(drill 0.762)
			(layers "*.Cu" "*.Mask")
			(remove_unused_layers no)
			(net "P12V")
			(clearance 0.0508)
			(thermal_gap 0.0508)
		)
		(pad "C6" thru_hole circle
			(at 5.999988 11.999976)
			(size 1.1684 1.1684)
			(drill 0.762)
			(layers "*.Cu" "*.Mask")
			(remove_unused_layers no)
			(net "P12V")
			(clearance 0.0508)
			(thermal_gap 0.0508)
		)
		(pad "D1" thru_hole circle
			(at 0 7.999984)
			(size 1.1684 1.1684)
			(drill 0.762)
			(layers "*.Cu" "*.Mask")
			(remove_unused_layers no)
			(net "GND")
			(clearance 0.0508)
			(thermal_gap 0.0508)
		)
		(pad "D2" thru_hole circle
			(at 0 9.99998)
			(size 1.1684 1.1684)
			(drill 0.762)
			(layers "*.Cu" "*.Mask")
			(remove_unused_layers no)
			(net "GND")
			(clearance 0.0508)
			(thermal_gap 0.0508)
		)
		(pad "D3" thru_hole circle
			(at 0 11.999976)
			(size 1.1684 1.1684)
			(drill 0.762)
			(layers "*.Cu" "*.Mask")
			(remove_unused_layers no)
			(net "GND")
			(clearance 0.0508)
			(thermal_gap 0.0508)
		)
		(pad "D4" thru_hole circle
			(at 1.999996 7.999984)
			(size 1.1684 1.1684)
			(drill 0.762)
			(layers "*.Cu" "*.Mask")
			(remove_unused_layers no)
			(net "GND")
			(clearance 0.0508)
			(thermal_gap 0.0508)
		)
		(pad "D5" thru_hole circle
			(at 1.999996 9.99998)
			(size 1.1684 1.1684)
			(drill 0.762)
			(layers "*.Cu" "*.Mask")
			(remove_unused_layers no)
			(net "GND")
			(clearance 0.0508)
			(thermal_gap 0.0508)
		)
		(pad "D6" thru_hole circle
			(at 1.999996 11.999976)
			(size 1.1684 1.1684)
			(drill 0.762)
			(layers "*.Cu" "*.Mask")
			(remove_unused_layers no)
			(net "GND")
			(clearance 0.0508)
			(thermal_gap 0.0508)
		)
	)
)
